(kicad_pcb
	(version 20260206)
	(generator "pcbnew")
	(generator_version "10.0")
	(general
		(thickness 1.6)
		(legacy_teardrops no)
	)
	(paper "A4")
	(title_block
		(title "04192023_DAF0TMB3IC0_F0TG_MB_C_brd_V02_OCP.brd")
		(comment 1 "Grand Teton / footprints 3047-3053 of 8354")
	)
	(layers
		(0 "F.Cu" signal "TOP")
		(4 "In1.Cu" signal "GND")
		(6 "In2.Cu" signal "IN1")
		(8 "In3.Cu" signal "GND1")
		(10 "In4.Cu" signal "IN2")
		(12 "In5.Cu" signal "GND2")
		(14 "In6.Cu" signal "IN3")
		(16 "In7.Cu" signal "GND3")
		(18 "In8.Cu" signal "VCC")
		(20 "In9.Cu" signal "VCC1")
		(22 "In10.Cu" signal "GND4")
		(24 "In11.Cu" signal "IN4")
		(26 "In12.Cu" signal "GND5")
		(28 "In13.Cu" signal "IN5")
		(30 "In14.Cu" signal "GND6")
		(32 "In15.Cu" signal "IN6")
		(34 "In16.Cu" signal "GND7")
		(2 "B.Cu" signal "BOTTOM")
		(9 "F.Adhes" user "F.Adhesive")
		(11 "B.Adhes" user "B.Adhesive")
		(13 "F.Paste" user "Package Geometry/Pastemask Top")
		(15 "B.Paste" user "Package Geometry/Pastemask Bottom")
		(5 "F.SilkS" user "Ref Des/Silkscreen Top")
		(7 "B.SilkS" user "Ref Des/Silkscreen Bottom")
		(1 "F.Mask" user "Board Geometry/Soldermask Top")
		(3 "B.Mask" user "Board Geometry/Soldermask Bottom")
		(17 "Dwgs.User" user "User.Drawings")
		(19 "Cmts.User" user "User.Comments")
		(21 "Eco1.User" user "User.Eco1")
		(23 "Eco2.User" user "User.Eco2")
		(25 "Edge.Cuts" user "Board Geometry/Outline")
		(27 "Margin" user)
		(31 "F.CrtYd" user "Package Geometry/Place Bound Top")
		(29 "B.CrtYd" user "Package Geometry/Place Bound Bottom")
		(35 "F.Fab" user "Ref Des/Assembly Top")
		(33 "B.Fab" user "Ref Des/Assembly Bottom")
	)
	(footprint ""
		(layer "F.Cu")
		(at 251.474224 -131.067556)
		(property "Reference" "R610"
			(at 0 0 0)
			(layer "F.SilkS")
			(hide yes)
			(effects
				(font
					(size 1.27 1.27)
				)
			)
		)
		(property "Value" ""
			(at 0 0 0)
			(layer "F.Fab")
			(effects
				(font
					(size 1.27 1.27)
				)
			)
		)
		(duplicate_pad_numbers_are_jumpers no)
		(fp_line
			(start -0.7874 -0.4064)
			(end 0.7874 -0.4064)
			(stroke
				(width 0.1524)
				(type default)
			)
			(layer "F.SilkS")
		)
		(fp_line
			(start -0.7874 0.4064)
			(end -0.7874 -0.4064)
			(stroke
				(width 0.1524)
				(type default)
			)
			(layer "F.SilkS")
		)
		(fp_line
			(start 0.7874 -0.4064)
			(end 0.7874 0.4064)
			(stroke
				(width 0.1524)
				(type default)
			)
			(layer "F.SilkS")
		)
		(fp_line
			(start 0.7874 0.4064)
			(end -0.7874 0.4064)
			(stroke
				(width 0.1524)
				(type default)
			)
			(layer "F.SilkS")
		)
		(fp_line
			(start -0.67945 -0.305054)
			(end -0.12065 -0.305054)
			(stroke
				(width 0.1)
				(type default)
			)
			(layer "F.Fab")
		)
		(fp_line
			(start -0.67945 0.3048)
			(end -0.67945 -0.305054)
			(stroke
				(width 0.1)
				(type default)
			)
			(layer "F.Fab")
		)
		(fp_line
			(start -0.12065 -0.305054)
			(end -0.12065 -0.2794)
			(stroke
				(width 0.1)
				(type default)
			)
			(layer "F.Fab")
		)
		(fp_line
			(start -0.12065 -0.2794)
			(end 0.12065 -0.2794)
			(stroke
				(width 0.1)
				(type default)
			)
			(layer "F.Fab")
		)
		(fp_line
			(start -0.12065 0.2794)
			(end -0.12065 0.3048)
			(stroke
				(width 0.1)
				(type default)
			)
			(layer "F.Fab")
		)
		(fp_line
			(start -0.12065 0.3048)
			(end -0.67945 0.3048)
			(stroke
				(width 0.1)
				(type default)
			)
			(layer "F.Fab")
		)
		(fp_line
			(start 0.120396 0.2794)
			(end -0.12065 0.2794)
			(stroke
				(width 0.1)
				(type default)
			)
			(layer "F.Fab")
		)
		(fp_line
			(start 0.120396 0.3048)
			(end 0.120396 0.2794)
			(stroke
				(width 0.1)
				(type default)
			)
			(layer "F.Fab")
		)
		(fp_line
			(start 0.12065 -0.3048)
			(end 0.67945 -0.3048)
			(stroke
				(width 0.1)
				(type default)
			)
			(layer "F.Fab")
		)
		(fp_line
			(start 0.12065 -0.2794)
			(end 0.12065 -0.3048)
			(stroke
				(width 0.1)
				(type default)
			)
			(layer "F.Fab")
		)
		(fp_line
			(start 0.67945 -0.3048)
			(end 0.67945 0.3048)
			(stroke
				(width 0.1)
				(type default)
			)
			(layer "F.Fab")
		)
		(fp_line
			(start 0.67945 0.3048)
			(end 0.120396 0.3048)
			(stroke
				(width 0.1)
				(type default)
			)
			(layer "F.Fab")
		)
		(pad "1" smd circle
			(at -0.40005 0)
			(size 0 0)
			(layers "F.Cu" "F.Mask" "F.Paste")
			(net "P3V3_AUX")
		)
		(pad "2" smd circle
			(at 0.40005 0)
			(size 0 0)
			(layers "F.Cu" "F.Mask" "F.Paste")
			(net "SPI_CPU0_LVC3_SCM_CS0_N")
		)
	)
	(footprint ""
		(layer "F.Cu")
		(at 412.472886 -73.848468 180)
		(property "Reference" "R48"
			(at 0 0 180)
			(layer "F.SilkS")
			(hide yes)
			(effects
				(font
					(size 1.27 1.27)
				)
			)
		)
		(property "Value" ""
			(at 0 0 180)
			(layer "F.Fab")
			(effects
				(font
					(size 1.27 1.27)
				)
			)
		)
		(duplicate_pad_numbers_are_jumpers no)
		(fp_line
			(start 0.7874 0.4064)
			(end -0.7874 0.4064)
			(stroke
				(width 0.1524)
				(type default)
			)
			(layer "F.SilkS")
		)
		(fp_line
			(start 0.7874 -0.4064)
			(end 0.7874 0.4064)
			(stroke
				(width 0.1524)
				(type default)
			)
			(layer "F.SilkS")
		)
		(fp_line
			(start -0.7874 0.4064)
			(end -0.7874 -0.4064)
			(stroke
				(width 0.1524)
				(type default)
			)
			(layer "F.SilkS")
		)
		(fp_line
			(start -0.7874 -0.4064)
			(end 0.7874 -0.4064)
			(stroke
				(width 0.1524)
				(type default)
			)
			(layer "F.SilkS")
		)
		(fp_line
			(start 0.67945 0.3048)
			(end 0.120396 0.3048)
			(stroke
				(width 0.1)
				(type default)
			)
			(layer "F.Fab")
		)
		(fp_line
			(start 0.67945 -0.3048)
			(end 0.67945 0.3048)
			(stroke
				(width 0.1)
				(type default)
			)
			(layer "F.Fab")
		)
		(fp_line
			(start 0.12065 -0.2794)
			(end 0.12065 -0.3048)
			(stroke
				(width 0.1)
				(type default)
			)
			(layer "F.Fab")
		)
		(fp_line
			(start 0.12065 -0.3048)
			(end 0.67945 -0.3048)
			(stroke
				(width 0.1)
				(type default)
			)
			(layer "F.Fab")
		)
		(fp_line
			(start 0.120396 0.3048)
			(end 0.120396 0.2794)
			(stroke
				(width 0.1)
				(type default)
			)
			(layer "F.Fab")
		)
		(fp_line
			(start 0.120396 0.2794)
			(end -0.12065 0.2794)
			(stroke
				(width 0.1)
				(type default)
			)
			(layer "F.Fab")
		)
		(fp_line
			(start -0.12065 0.3048)
			(end -0.67945 0.3048)
			(stroke
				(width 0.1)
				(type default)
			)
			(layer "F.Fab")
		)
		(fp_line
			(start -0.12065 0.2794)
			(end -0.12065 0.3048)
			(stroke
				(width 0.1)
				(type default)
			)
			(layer "F.Fab")
		)
		(fp_line
			(start -0.12065 -0.2794)
			(end 0.12065 -0.2794)
			(stroke
				(width 0.1)
				(type default)
			)
			(layer "F.Fab")
		)
		(fp_line
			(start -0.12065 -0.305054)
			(end -0.12065 -0.2794)
			(stroke
				(width 0.1)
				(type default)
			)
			(layer "F.Fab")
		)
		(fp_line
			(start -0.67945 0.3048)
			(end -0.67945 -0.305054)
			(stroke
				(width 0.1)
				(type default)
			)
			(layer "F.Fab")
		)
		(fp_line
			(start -0.67945 -0.305054)
			(end -0.12065 -0.305054)
			(stroke
				(width 0.1)
				(type default)
			)
			(layer "F.Fab")
		)
		(pad "1" smd circle
			(at -0.40005 0 180)
			(size 0 0)
			(layers "F.Cu" "F.Mask" "F.Paste")
			(net "SMB_OCP_SFF_3V3AUX_BUF_R_SDA")
		)
		(pad "2" smd circle
			(at 0.40005 0 180)
			(size 0 0)
			(layers "F.Cu" "F.Mask" "F.Paste")
			(net "SMB_OCP_SFF_3V3AUX_BUF_SDA")
		)
	)
	(footprint ""
		(layer "F.Cu")
		(at 20.21586 -347.8149)
		(property "Reference" "H11"
			(at 0.9144 3.91287 0)
			(unlocked yes)
			(layer "F.SilkS")
			(effects
				(font
					(size 0.7874 0.5842)
					(thickness 0.1524)
				)
				(justify left)
			)
		)
		(property "Value" ""
			(at 0 0 0)
			(layer "F.Fab")
			(effects
				(font
					(size 1.27 1.27)
				)
			)
		)
		(duplicate_pad_numbers_are_jumpers no)
		(pad "1" thru_hole circle
			(at 0 0)
			(size 6.1976 6.1976)
			(drill 3.7338)
			(layers "*.Cu" "*.Mask")
			(remove_unused_layers no)
			(net "GND")
			(clearance -0.9779)
			(padstack
				(mode front_inner_back)
				(layer "Inner"
					(shape circle)
					(size 5.5372 5.5372)
					(clearance -0.6477)
				)
				(layer "B.Cu"
					(shape circle)
					(size 6.1976 6.1976)
					(clearance -0.9779)
				)
			)
		)
	)
	(footprint ""
		(layer "F.Cu")
		(at 293.79418 -351.368106 -90)
		(property "Reference" "PC156"
			(at 0 0 270)
			(layer "F.SilkS")
			(hide yes)
			(effects
				(font
					(size 1.27 1.27)
				)
			)
		)
		(property "Value" ""
			(at 0 0 270)
			(layer "F.Fab")
			(effects
				(font
					(size 1.27 1.27)
				)
			)
		)
		(duplicate_pad_numbers_are_jumpers no)
		(fp_line
			(start -0.7874 0.4064)
			(end -0.7874 -0.4064)
			(stroke
				(width 0.1524)
				(type default)
			)
			(layer "F.SilkS")
		)
		(fp_line
			(start 0.7874 0.4064)
			(end -0.7874 0.4064)
			(stroke
				(width 0.1524)
				(type default)
			)
			(layer "F.SilkS")
		)
		(fp_line
			(start -0.7874 -0.4064)
			(end 0.7874 -0.4064)
			(stroke
				(width 0.1524)
				(type default)
			)
			(layer "F.SilkS")
		)
		(fp_line
			(start 0.7874 -0.4064)
			(end 0.7874 0.4064)
			(stroke
				(width 0.1524)
				(type default)
			)
			(layer "F.SilkS")
		)
		(fp_line
			(start -0.67945 0.3048)
			(end -0.67945 -0.305054)
			(stroke
				(width 0.1)
				(type default)
			)
			(layer "F.Fab")
		)
		(fp_line
			(start -0.12065 0.3048)
			(end -0.67945 0.3048)
			(stroke
				(width 0.1)
				(type default)
			)
			(layer "F.Fab")
		)
		(fp_line
			(start 0.120396 0.3048)
			(end 0.120396 0.2794)
			(stroke
				(width 0.1)
				(type default)
			)
			(layer "F.Fab")
		)
		(fp_line
			(start 0.67945 0.3048)
			(end 0.120396 0.3048)
			(stroke
				(width 0.1)
				(type default)
			)
			(layer "F.Fab")
		)
		(fp_line
			(start -0.12065 0.2794)
			(end -0.12065 0.3048)
			(stroke
				(width 0.1)
				(type default)
			)
			(layer "F.Fab")
		)
		(fp_line
			(start 0.120396 0.2794)
			(end -0.12065 0.2794)
			(stroke
				(width 0.1)
				(type default)
			)
			(layer "F.Fab")
		)
		(fp_line
			(start -0.12065 -0.2794)
			(end 0.12065 -0.2794)
			(stroke
				(width 0.1)
				(type default)
			)
			(layer "F.Fab")
		)
		(fp_line
			(start 0.12065 -0.2794)
			(end 0.12065 -0.3048)
			(stroke
				(width 0.1)
				(type default)
			)
			(layer "F.Fab")
		)
		(fp_line
			(start 0.12065 -0.3048)
			(end 0.67945 -0.3048)
			(stroke
				(width 0.1)
				(type default)
			)
			(layer "F.Fab")
		)
		(fp_line
			(start 0.67945 -0.3048)
			(end 0.67945 0.3048)
			(stroke
				(width 0.1)
				(type default)
			)
			(layer "F.Fab")
		)
		(fp_line
			(start -0.67945 -0.305054)
			(end -0.12065 -0.305054)
			(stroke
				(width 0.1)
				(type default)
			)
			(layer "F.Fab")
		)
		(fp_line
			(start -0.12065 -0.305054)
			(end -0.12065 -0.2794)
			(stroke
				(width 0.1)
				(type default)
			)
			(layer "F.Fab")
		)
		(pad "1" smd circle
			(at -0.40005 0 270)
			(size 0 0)
			(layers "F.Cu" "F.Mask" "F.Paste")
			(net "SW_PVDDIO_P0_BOOT2_R")
		)
		(pad "2" smd circle
			(at 0.40005 0 270)
			(size 0 0)
			(layers "F.Cu" "F.Mask" "F.Paste")
			(net "SW_PVDDIO_P0_BOOTR2")
		)
	)
	(footprint ""
		(layer "F.Cu")
		(at 17.380458 -418.690298 -90)
		(property "Reference" "R6180"
			(at 0 0 270)
			(layer "F.SilkS")
			(hide yes)
			(effects
				(font
					(size 1.27 1.27)
				)
			)
		)
		(property "Value" ""
			(at 0 0 270)
			(layer "F.Fab")
			(effects
				(font
					(size 1.27 1.27)
				)
			)
		)
		(duplicate_pad_numbers_are_jumpers no)
		(fp_line
			(start -0.7874 0.4064)
			(end -0.7874 -0.4064)
			(stroke
				(width 0.1524)
				(type default)
			)
			(layer "F.SilkS")
		)
		(fp_line
			(start 0.7874 0.4064)
			(end -0.7874 0.4064)
			(stroke
				(width 0.1524)
				(type default)
			)
			(layer "F.SilkS")
		)
		(fp_line
			(start -0.7874 -0.4064)
			(end 0.7874 -0.4064)
			(stroke
				(width 0.1524)
				(type default)
			)
			(layer "F.SilkS")
		)
		(fp_line
			(start 0.7874 -0.4064)
			(end 0.7874 0.4064)
			(stroke
				(width 0.1524)
				(type default)
			)
			(layer "F.SilkS")
		)
		(fp_line
			(start -0.67945 0.3048)
			(end -0.67945 -0.305054)
			(stroke
				(width 0.1)
				(type default)
			)
			(layer "F.Fab")
		)
		(fp_line
			(start -0.12065 0.3048)
			(end -0.67945 0.3048)
			(stroke
				(width 0.1)
				(type default)
			)
			(layer "F.Fab")
		)
		(fp_line
			(start 0.120396 0.3048)
			(end 0.120396 0.2794)
			(stroke
				(width 0.1)
				(type default)
			)
			(layer "F.Fab")
		)
		(fp_line
			(start 0.67945 0.3048)
			(end 0.120396 0.3048)
			(stroke
				(width 0.1)
				(type default)
			)
			(layer "F.Fab")
		)
		(fp_line
			(start -0.12065 0.2794)
			(end -0.12065 0.3048)
			(stroke
				(width 0.1)
				(type default)
			)
			(layer "F.Fab")
		)
		(fp_line
			(start 0.120396 0.2794)
			(end -0.12065 0.2794)
			(stroke
				(width 0.1)
				(type default)
			)
			(layer "F.Fab")
		)
		(fp_line
			(start -0.12065 -0.2794)
			(end 0.12065 -0.2794)
			(stroke
				(width 0.1)
				(type default)
			)
			(layer "F.Fab")
		)
		(fp_line
			(start 0.12065 -0.2794)
			(end 0.12065 -0.3048)
			(stroke
				(width 0.1)
				(type default)
			)
			(layer "F.Fab")
		)
		(fp_line
			(start 0.12065 -0.3048)
			(end 0.67945 -0.3048)
			(stroke
				(width 0.1)
				(type default)
			)
			(layer "F.Fab")
		)
		(fp_line
			(start 0.67945 -0.3048)
			(end 0.67945 0.3048)
			(stroke
				(width 0.1)
				(type default)
			)
			(layer "F.Fab")
		)
		(fp_line
			(start -0.67945 -0.305054)
			(end -0.12065 -0.305054)
			(stroke
				(width 0.1)
				(type default)
			)
			(layer "F.Fab")
		)
		(fp_line
			(start -0.12065 -0.305054)
			(end -0.12065 -0.2794)
			(stroke
				(width 0.1)
				(type default)
			)
			(layer "F.Fab")
		)
		(pad "1" smd circle
			(at -0.40005 0 270)
			(size 0 0)
			(layers "F.Cu" "F.Mask" "F.Paste")
			(net "FM_P2E_BUF2_VOD_SEL")
		)
		(pad "2" smd circle
			(at 0.40005 0 270)
			(size 0 0)
			(layers "F.Cu" "F.Mask" "F.Paste")
			(net "GND")
		)
	)
	(footprint ""
		(layer "F.Cu")
		(at 120.68175 -23.005796)
		(property "Reference" "R6274"
			(at 0 0 0)
			(layer "F.SilkS")
			(hide yes)
			(effects
				(font
					(size 1.27 1.27)
				)
			)
		)
		(property "Value" ""
			(at 0 0 0)
			(layer "F.Fab")
			(effects
				(font
					(size 1.27 1.27)
				)
			)
		)
		(duplicate_pad_numbers_are_jumpers no)
		(fp_line
			(start -0.7874 -0.4064)
			(end 0.7874 -0.4064)
			(stroke
				(width 0.1524)
				(type default)
			)
			(layer "F.SilkS")
		)
		(fp_line
			(start -0.7874 0.4064)
			(end -0.7874 -0.4064)
			(stroke
				(width 0.1524)
				(type default)
			)
			(layer "F.SilkS")
		)
		(fp_line
			(start 0.7874 -0.4064)
			(end 0.7874 0.4064)
			(stroke
				(width 0.1524)
				(type default)
			)
			(layer "F.SilkS")
		)
		(fp_line
			(start 0.7874 0.4064)
			(end -0.7874 0.4064)
			(stroke
				(width 0.1524)
				(type default)
			)
			(layer "F.SilkS")
		)
		(fp_line
			(start -0.67945 -0.305054)
			(end -0.12065 -0.305054)
			(stroke
				(width 0.1)
				(type default)
			)
			(layer "F.Fab")
		)
		(fp_line
			(start -0.67945 0.3048)
			(end -0.67945 -0.305054)
			(stroke
				(width 0.1)
				(type default)
			)
			(layer "F.Fab")
		)
		(fp_line
			(start -0.12065 -0.305054)
			(end -0.12065 -0.2794)
			(stroke
				(width 0.1)
				(type default)
			)
			(layer "F.Fab")
		)
		(fp_line
			(start -0.12065 -0.2794)
			(end 0.12065 -0.2794)
			(stroke
				(width 0.1)
				(type default)
			)
			(layer "F.Fab")
		)
		(fp_line
			(start -0.12065 0.2794)
			(end -0.12065 0.3048)
			(stroke
				(width 0.1)
				(type default)
			)
			(layer "F.Fab")
		)
		(fp_line
			(start -0.12065 0.3048)
			(end -0.67945 0.3048)
			(stroke
				(width 0.1)
				(type default)
			)
			(layer "F.Fab")
		)
		(fp_line
			(start 0.120396 0.2794)
			(end -0.12065 0.2794)
			(stroke
				(width 0.1)
				(type default)
			)
			(layer "F.Fab")
		)
		(fp_line
			(start 0.120396 0.3048)
			(end 0.120396 0.2794)
			(stroke
				(width 0.1)
				(type default)
			)
			(layer "F.Fab")
		)
		(fp_line
			(start 0.12065 -0.3048)
			(end 0.67945 -0.3048)
			(stroke
				(width 0.1)
				(type default)
			)
			(layer "F.Fab")
		)
		(fp_line
			(start 0.12065 -0.2794)
			(end 0.12065 -0.3048)
			(stroke
				(width 0.1)
				(type default)
			)
			(layer "F.Fab")
		)
		(fp_line
			(start 0.67945 -0.3048)
			(end 0.67945 0.3048)
			(stroke
				(width 0.1)
				(type default)
			)
			(layer "F.Fab")
		)
		(fp_line
			(start 0.67945 0.3048)
			(end 0.120396 0.3048)
			(stroke
				(width 0.1)
				(type default)
			)
			(layer "F.Fab")
		)
		(pad "1" smd circle
			(at -0.40005 0)
			(size 0 0)
			(layers "F.Cu" "F.Mask" "F.Paste")
			(net "USB_HUB2_TI_VDD33_MRP_PROG_FUNC7")
		)
		(pad "2" smd circle
			(at 0.40005 0)
			(size 0 0)
			(layers "F.Cu" "F.Mask" "F.Paste")
			(net "P3V3_AUX_CPU0_USB2_AVDD33")
		)
	)
	(footprint ""
		(layer "F.Cu")
		(at 331.517244 -381.41783 -90)
		(property "Reference" "C961"
			(at 0 0 270)
			(layer "F.SilkS")
			(hide yes)
			(effects
				(font
					(size 1.27 1.27)
				)
			)
		)
		(property "Value" ""
			(at 0 0 270)
			(layer "F.Fab")
			(effects
				(font
					(size 1.27 1.27)
				)
			)
		)
		(duplicate_pad_numbers_are_jumpers no)
		(fp_line
			(start -0.299974 0.150114)
			(end -0.299974 -0.150114)
			(stroke
				(width 0.1)
				(type default)
			)
			(layer "F.Fab")
		)
		(fp_line
			(start 0.299974 0.150114)
			(end -0.299974 0.150114)
			(stroke
				(width 0.1)
				(type default)
			)
			(layer "F.Fab")
		)
		(fp_line
			(start -0.299974 -0.150114)
			(end 0.299974 -0.150114)
			(stroke
				(width 0.1)
				(type default)
			)
			(layer "F.Fab")
		)
		(fp_line
			(start 0.299974 -0.150114)
			(end 0.299974 0.150114)
			(stroke
				(width 0.1)
				(type default)
			)
			(layer "F.Fab")
		)
		(pad "1" smd rect
			(at -0.2667 0 270)
			(size 0.3048 0.381)
			(layers "F.Cu" "F.Mask" "F.Paste")
			(net "P5E_CPU0_P1_TX_C_DP<2>")
		)
		(pad "2" smd rect
			(at 0.2667 0 270)
			(size 0.3048 0.381)
			(layers "F.Cu" "F.Mask" "F.Paste")
			(net "P5E_CPU0_P1_TX_DP<2>")
		)
	)
)
